(kicad_pcb
	(version 20260206)
	(generator "pcbnew")
	(generator_version "10.0")
	(general
		(thickness 1.6)
		(legacy_teardrops no)
	)
	(paper "A4")
	(title_block
		(title "01162023_DA0F0TEBIF0_F0T_Expander_BD_F_brd_V02_OCP.brd")
		(comment 1 "Grand Teton / footprints 7336-7344 of 9728")
	)
	(layers
		(0 "F.Cu" signal "TOP")
		(4 "In1.Cu" signal "GND")
		(6 "In2.Cu" signal "VCC")
		(8 "In3.Cu" signal "VCC1")
		(10 "In4.Cu" signal "GND1")
		(12 "In5.Cu" signal "IN1")
		(14 "In6.Cu" signal "GND2")
		(16 "In7.Cu" signal "IN2")
		(18 "In8.Cu" signal "GND3")
		(20 "In9.Cu" signal "IN3")
		(22 "In10.Cu" signal "GND4")
		(24 "In11.Cu" signal "IN4")
		(26 "In12.Cu" signal "GND5")
		(28 "In13.Cu" signal "IN5")
		(30 "In14.Cu" signal "GND6")
		(32 "In15.Cu" signal "IN6")
		(34 "In16.Cu" signal "GND7")
		(2 "B.Cu" signal "BOTTOM")
		(9 "F.Adhes" user "F.Adhesive")
		(11 "B.Adhes" user "B.Adhesive")
		(13 "F.Paste" user "Package Geometry/Pastemask Top")
		(15 "B.Paste" user "Package Geometry/Pastemask Bottom")
		(5 "F.SilkS" user "Ref Des/Silkscreen Top")
		(7 "B.SilkS" user "Ref Des/Silkscreen Bottom")
		(1 "F.Mask" user "Board Geometry/Soldermask Top")
		(3 "B.Mask" user "Board Geometry/Soldermask Bottom")
		(17 "Dwgs.User" user "User.Drawings")
		(19 "Cmts.User" user "User.Comments")
		(21 "Eco1.User" user "User.Eco1")
		(23 "Eco2.User" user "User.Eco2")
		(25 "Edge.Cuts" user "Board Geometry/Outline")
		(27 "Margin" user)
		(31 "F.CrtYd" user "Package Geometry/Place Bound Top")
		(29 "B.CrtYd" user "Package Geometry/Place Bound Bottom")
		(35 "F.Fab" user "Ref Des/Assembly Top")
		(33 "B.Fab" user "Ref Des/Assembly Bottom")
	)
	(footprint ""
		(layer "B.Cu")
		(at 163.874958 -298.00804 90)
		(property "Reference" "C3242"
			(at 0 0 90)
			(layer "B.SilkS")
			(hide yes)
			(effects
				(font
					(size 1.27 1.27)
				)
				(justify mirror)
			)
		)
		(property "Value" ""
			(at 0 0 90)
			(layer "B.Fab")
			(effects
				(font
					(size 1.27 1.27)
				)
				(justify mirror)
			)
		)
		(duplicate_pad_numbers_are_jumpers no)
		(fp_line
			(start 0.299974 -0.150114)
			(end -0.299974 -0.150114)
			(stroke
				(width 0.1)
				(type default)
			)
			(layer "B.Fab")
		)
		(fp_line
			(start -0.299974 -0.150114)
			(end -0.299974 0.150114)
			(stroke
				(width 0.1)
				(type default)
			)
			(layer "B.Fab")
		)
		(fp_line
			(start 0.299974 0.150114)
			(end 0.299974 -0.150114)
			(stroke
				(width 0.1)
				(type default)
			)
			(layer "B.Fab")
		)
		(fp_line
			(start -0.299974 0.150114)
			(end 0.299974 0.150114)
			(stroke
				(width 0.1)
				(type default)
			)
			(layer "B.Fab")
		)
		(pad "1" smd rect
			(at 0.2667 0 270)
			(size 0.3048 0.381)
			(layers "B.Cu" "B.Mask" "B.Paste")
			(net "SYSPLL_VDDA18_PEX1")
		)
		(pad "2" smd rect
			(at -0.2667 0 270)
			(size 0.3048 0.381)
			(layers "B.Cu" "B.Mask" "B.Paste")
			(net "GND")
		)
	)
	(footprint ""
		(layer "B.Cu")
		(at 363.305344 -324.163944 -90)
		(property "Reference" "C4384"
			(at 0 0 90)
			(layer "B.SilkS")
			(hide yes)
			(effects
				(font
					(size 1.27 1.27)
				)
				(justify mirror)
			)
		)
		(property "Value" ""
			(at 0 0 90)
			(layer "B.Fab")
			(effects
				(font
					(size 1.27 1.27)
				)
				(justify mirror)
			)
		)
		(duplicate_pad_numbers_are_jumpers no)
		(fp_line
			(start -1.2954 0.5842)
			(end 1.2954 0.5842)
			(stroke
				(width 0.1524)
				(type default)
			)
			(layer "B.SilkS")
		)
		(fp_line
			(start 1.2954 0.5842)
			(end 1.2954 -0.5842)
			(stroke
				(width 0.1524)
				(type default)
			)
			(layer "B.SilkS")
		)
		(fp_line
			(start -1.2954 -0.5842)
			(end -1.2954 0.5842)
			(stroke
				(width 0.1524)
				(type default)
			)
			(layer "B.SilkS")
		)
		(fp_line
			(start 1.2954 -0.5842)
			(end -1.2954 -0.5842)
			(stroke
				(width 0.1524)
				(type default)
			)
			(layer "B.SilkS")
		)
		(fp_line
			(start -0.8636 0.4572)
			(end 0.8636 0.4572)
			(stroke
				(width 0.1)
				(type default)
			)
			(layer "B.Fab")
		)
		(fp_line
			(start 0.8636 0.4572)
			(end 0.8636 0.4064)
			(stroke
				(width 0.1)
				(type default)
			)
			(layer "B.Fab")
		)
		(fp_line
			(start -1.1938 0.4064)
			(end -0.8636 0.4064)
			(stroke
				(width 0.1)
				(type default)
			)
			(layer "B.Fab")
		)
		(fp_line
			(start -0.8636 0.4064)
			(end -0.8636 0.4572)
			(stroke
				(width 0.1)
				(type default)
			)
			(layer "B.Fab")
		)
		(fp_line
			(start 0.8636 0.4064)
			(end 1.1938 0.4064)
			(stroke
				(width 0.1)
				(type default)
			)
			(layer "B.Fab")
		)
		(fp_line
			(start 1.1938 0.4064)
			(end 1.1938 -0.4064)
			(stroke
				(width 0.1)
				(type default)
			)
			(layer "B.Fab")
		)
		(fp_line
			(start -1.1938 -0.4064)
			(end -1.1938 0.4064)
			(stroke
				(width 0.1)
				(type default)
			)
			(layer "B.Fab")
		)
		(fp_line
			(start -0.8636 -0.4064)
			(end -1.1938 -0.4064)
			(stroke
				(width 0.1)
				(type default)
			)
			(layer "B.Fab")
		)
		(fp_line
			(start 0.8636 -0.4064)
			(end 0.8636 -0.4572)
			(stroke
				(width 0.1)
				(type default)
			)
			(layer "B.Fab")
		)
		(fp_line
			(start 1.1938 -0.4064)
			(end 0.8636 -0.4064)
			(stroke
				(width 0.1)
				(type default)
			)
			(layer "B.Fab")
		)
		(fp_line
			(start -0.8636 -0.4572)
			(end -0.8636 -0.4064)
			(stroke
				(width 0.1)
				(type default)
			)
			(layer "B.Fab")
		)
		(fp_line
			(start 0.8636 -0.4572)
			(end -0.8636 -0.4572)
			(stroke
				(width 0.1)
				(type default)
			)
			(layer "B.Fab")
		)
		(pad "1" smd rect
			(at 0.7366 0 180)
			(size 0.7112 0.8128)
			(layers "B.Cu" "B.Mask" "B.Paste")
			(net "P0V8_SERDES_VDDA_PEX3_C10")
		)
		(pad "2" smd rect
			(at -0.7366 0 180)
			(size 0.7112 0.8128)
			(layers "B.Cu" "B.Mask" "B.Paste")
			(net "GND")
		)
	)
	(footprint ""
		(layer "B.Cu")
		(at 414.599882 -290.199826 90)
		(property "Reference" "C1947"
			(at 0 0 90)
			(layer "B.SilkS")
			(hide yes)
			(effects
				(font
					(size 1.27 1.27)
				)
				(justify mirror)
			)
		)
		(property "Value" ""
			(at 0 0 90)
			(layer "B.Fab")
			(effects
				(font
					(size 1.27 1.27)
				)
				(justify mirror)
			)
		)
		(duplicate_pad_numbers_are_jumpers no)
		(fp_line
			(start 0.299974 -0.150114)
			(end -0.299974 -0.150114)
			(stroke
				(width 0.1)
				(type default)
			)
			(layer "B.Fab")
		)
		(fp_line
			(start -0.299974 -0.150114)
			(end -0.299974 0.150114)
			(stroke
				(width 0.1)
				(type default)
			)
			(layer "B.Fab")
		)
		(fp_line
			(start 0.299974 0.150114)
			(end 0.299974 -0.150114)
			(stroke
				(width 0.1)
				(type default)
			)
			(layer "B.Fab")
		)
		(fp_line
			(start -0.299974 0.150114)
			(end 0.299974 0.150114)
			(stroke
				(width 0.1)
				(type default)
			)
			(layer "B.Fab")
		)
		(pad "1" smd rect
			(at 0.2667 0 270)
			(size 0.3048 0.381)
			(layers "B.Cu" "B.Mask" "B.Paste")
			(net "P0V8_SERDES_VDDA_PEX3")
		)
		(pad "2" smd rect
			(at -0.2667 0 270)
			(size 0.3048 0.381)
			(layers "B.Cu" "B.Mask" "B.Paste")
			(net "GND")
		)
	)
	(footprint ""
		(layer "B.Cu")
		(at 332.862428 -227.33127 -90)
		(property "Reference" "C2088"
			(at 0 0 90)
			(layer "B.SilkS")
			(hide yes)
			(effects
				(font
					(size 1.27 1.27)
				)
				(justify mirror)
			)
		)
		(property "Value" ""
			(at 0 0 90)
			(layer "B.Fab")
			(effects
				(font
					(size 1.27 1.27)
				)
				(justify mirror)
			)
		)
		(duplicate_pad_numbers_are_jumpers no)
		(fp_line
			(start -0.69215 0.2921)
			(end 0.69215 0.2921)
			(stroke
				(width 0.1524)
				(type default)
			)
			(layer "B.SilkS")
		)
		(fp_line
			(start 0.69215 0.2921)
			(end 0.69215 -0.2921)
			(stroke
				(width 0.1524)
				(type default)
			)
			(layer "B.SilkS")
		)
		(fp_line
			(start -0.69215 -0.2921)
			(end -0.69215 0.2921)
			(stroke
				(width 0.1524)
				(type default)
			)
			(layer "B.SilkS")
		)
		(fp_line
			(start 0.69215 -0.2921)
			(end -0.69215 -0.2921)
			(stroke
				(width 0.1524)
				(type default)
			)
			(layer "B.SilkS")
		)
		(fp_line
			(start -0.51435 0.2794)
			(end 0.51435 0.2794)
			(stroke
				(width 0.1)
				(type default)
			)
			(layer "B.Fab")
		)
		(fp_line
			(start 0.51435 0.2794)
			(end 0.51435 -0.2794)
			(stroke
				(width 0.1)
				(type default)
			)
			(layer "B.Fab")
		)
		(fp_line
			(start -0.51435 -0.2794)
			(end -0.51435 0.2794)
			(stroke
				(width 0.1)
				(type default)
			)
			(layer "B.Fab")
		)
		(fp_line
			(start 0.51435 -0.2794)
			(end -0.51435 -0.2794)
			(stroke
				(width 0.1)
				(type default)
			)
			(layer "B.Fab")
		)
		(pad "1" smd circle
			(at 0.40005 0 90)
			(size 0 0)
			(layers "B.Cu" "B.Mask" "B.Paste")
			(net "P3V3_FPGA_VCCIO5")
		)
		(pad "2" smd circle
			(at -0.40005 0 90)
			(size 0 0)
			(layers "B.Cu" "B.Mask" "B.Paste")
			(net "GND")
		)
		(zone
			(layer "B.Cu")
			(hatch none 0.5)
			(connect_pads
				(clearance 0)
			)
			(min_thickness 0.25)
			(keepout
				(tracks not_allowed)
				(vias allowed)
				(pads allowed)
				(copperpour not_allowed)
				(footprints allowed)
			)
			(placement
				(enabled no)
				(sheetname "")
			)
			(fill
				(thermal_gap 0.5)
				(thermal_bridge_width 0.5)
				(island_removal_mode 0)
			)
			(polygon
				(pts
					(xy 332.774798 -227.14077) (xy 332.716632 -227.23221) (xy 332.716632 -227.4316) (xy 332.774798 -227.52177)
					(xy 332.950058 -227.52177) (xy 333.008478 -227.4316) (xy 333.008478 -227.23221) (xy 332.950312 -227.14077)
				)
			)
		)
	)
	(footprint ""
		(layer "B.Cu")
		(at 414.599882 -292.099746 90)
		(property "Reference" "C1960"
			(at 0 0 90)
			(layer "B.SilkS")
			(hide yes)
			(effects
				(font
					(size 1.27 1.27)
				)
				(justify mirror)
			)
		)
		(property "Value" ""
			(at 0 0 90)
			(layer "B.Fab")
			(effects
				(font
					(size 1.27 1.27)
				)
				(justify mirror)
			)
		)
		(duplicate_pad_numbers_are_jumpers no)
		(fp_line
			(start 0.299974 -0.150114)
			(end -0.299974 -0.150114)
			(stroke
				(width 0.1)
				(type default)
			)
			(layer "B.Fab")
		)
		(fp_line
			(start -0.299974 -0.150114)
			(end -0.299974 0.150114)
			(stroke
				(width 0.1)
				(type default)
			)
			(layer "B.Fab")
		)
		(fp_line
			(start 0.299974 0.150114)
			(end 0.299974 -0.150114)
			(stroke
				(width 0.1)
				(type default)
			)
			(layer "B.Fab")
		)
		(fp_line
			(start -0.299974 0.150114)
			(end 0.299974 0.150114)
			(stroke
				(width 0.1)
				(type default)
			)
			(layer "B.Fab")
		)
		(pad "1" smd rect
			(at 0.2667 0 270)
			(size 0.3048 0.381)
			(layers "B.Cu" "B.Mask" "B.Paste")
			(net "P0V8_SERDES_VDDA_PEX3")
		)
		(pad "2" smd rect
			(at -0.2667 0 270)
			(size 0.3048 0.381)
			(layers "B.Cu" "B.Mask" "B.Paste")
			(net "GND")
		)
	)
	(footprint ""
		(layer "B.Cu")
		(at 160.549844 -293.99992)
		(property "Reference" "C3162"
			(at 0 0 0)
			(layer "B.SilkS")
			(hide yes)
			(effects
				(font
					(size 1.27 1.27)
				)
				(justify mirror)
			)
		)
		(property "Value" ""
			(at 0 0 0)
			(layer "B.Fab")
			(effects
				(font
					(size 1.27 1.27)
				)
				(justify mirror)
			)
		)
		(duplicate_pad_numbers_are_jumpers no)
		(fp_line
			(start -0.299974 -0.150114)
			(end -0.299974 0.150114)
			(stroke
				(width 0.1)
				(type default)
			)
			(layer "B.Fab")
		)
		(fp_line
			(start -0.299974 0.150114)
			(end 0.299974 0.150114)
			(stroke
				(width 0.1)
				(type default)
			)
			(layer "B.Fab")
		)
		(fp_line
			(start 0.299974 -0.150114)
			(end -0.299974 -0.150114)
			(stroke
				(width 0.1)
				(type default)
			)
			(layer "B.Fab")
		)
		(fp_line
			(start 0.299974 0.150114)
			(end 0.299974 -0.150114)
			(stroke
				(width 0.1)
				(type default)
			)
			(layer "B.Fab")
		)
		(pad "1" smd rect
			(at 0.2667 0 180)
			(size 0.3048 0.381)
			(layers "B.Cu" "B.Mask" "B.Paste")
			(net "P1V8_PEX")
		)
		(pad "2" smd rect
			(at -0.2667 0 180)
			(size 0.3048 0.381)
			(layers "B.Cu" "B.Mask" "B.Paste")
			(net "GND")
		)
	)
	(footprint ""
		(layer "B.Cu")
		(at 303.954942 -97.663 180)
		(property "Reference" "R277"
			(at 0 0 0)
			(layer "B.SilkS")
			(hide yes)
			(effects
				(font
					(size 1.27 1.27)
				)
				(justify mirror)
			)
		)
		(property "Value" ""
			(at 0 0 0)
			(layer "B.Fab")
			(effects
				(font
					(size 1.27 1.27)
				)
				(justify mirror)
			)
		)
		(duplicate_pad_numbers_are_jumpers no)
		(fp_line
			(start 0.7874 0.4064)
			(end 0.7874 -0.4064)
			(stroke
				(width 0.1524)
				(type default)
			)
			(layer "B.SilkS")
		)
		(fp_line
			(start 0.7874 -0.4064)
			(end -0.7874 -0.4064)
			(stroke
				(width 0.1524)
				(type default)
			)
			(layer "B.SilkS")
		)
		(fp_line
			(start -0.7874 0.4064)
			(end 0.7874 0.4064)
			(stroke
				(width 0.1524)
				(type default)
			)
			(layer "B.SilkS")
		)
		(fp_line
			(start -0.7874 -0.4064)
			(end -0.7874 0.4064)
			(stroke
				(width 0.1524)
				(type default)
			)
			(layer "B.SilkS")
		)
		(fp_line
			(start 0.67945 0.3048)
			(end 0.67945 -0.305054)
			(stroke
				(width 0.1)
				(type default)
			)
			(layer "B.Fab")
		)
		(fp_line
			(start 0.67945 -0.305054)
			(end 0.12065 -0.305054)
			(stroke
				(width 0.1)
				(type default)
			)
			(layer "B.Fab")
		)
		(fp_line
			(start 0.12065 0.3048)
			(end 0.67945 0.3048)
			(stroke
				(width 0.1)
				(type default)
			)
			(layer "B.Fab")
		)
		(fp_line
			(start 0.12065 0.2794)
			(end 0.12065 0.3048)
			(stroke
				(width 0.1)
				(type default)
			)
			(layer "B.Fab")
		)
		(fp_line
			(start 0.12065 -0.2794)
			(end -0.12065 -0.2794)
			(stroke
				(width 0.1)
				(type default)
			)
			(layer "B.Fab")
		)
		(fp_line
			(start 0.12065 -0.305054)
			(end 0.12065 -0.2794)
			(stroke
				(width 0.1)
				(type default)
			)
			(layer "B.Fab")
		)
		(fp_line
			(start -0.120396 0.3048)
			(end -0.120396 0.2794)
			(stroke
				(width 0.1)
				(type default)
			)
			(layer "B.Fab")
		)
		(fp_line
			(start -0.120396 0.2794)
			(end 0.12065 0.2794)
			(stroke
				(width 0.1)
				(type default)
			)
			(layer "B.Fab")
		)
		(fp_line
			(start -0.12065 -0.2794)
			(end -0.12065 -0.3048)
			(stroke
				(width 0.1)
				(type default)
			)
			(layer "B.Fab")
		)
		(fp_line
			(start -0.12065 -0.3048)
			(end -0.67945 -0.3048)
			(stroke
				(width 0.1)
				(type default)
			)
			(layer "B.Fab")
		)
		(fp_line
			(start -0.67945 0.3048)
			(end -0.120396 0.3048)
			(stroke
				(width 0.1)
				(type default)
			)
			(layer "B.Fab")
		)
		(fp_line
			(start -0.67945 -0.3048)
			(end -0.67945 0.3048)
			(stroke
				(width 0.1)
				(type default)
			)
			(layer "B.Fab")
		)
		(pad "1" smd circle
			(at 0.40005 0)
			(size 0 0)
			(layers "B.Cu" "B.Mask" "B.Paste")
			(net "PWRGD_NIC5_PWR_GOOD")
		)
		(pad "2" smd circle
			(at -0.40005 0)
			(size 0 0)
			(layers "B.Cu" "B.Mask" "B.Paste")
			(net "GND")
		)
	)
	(footprint ""
		(layer "B.Cu")
		(at 413.649922 -292.099746 90)
		(property "Reference" "C1933"
			(at 0 0 90)
			(layer "B.SilkS")
			(hide yes)
			(effects
				(font
					(size 1.27 1.27)
				)
				(justify mirror)
			)
		)
		(property "Value" ""
			(at 0 0 90)
			(layer "B.Fab")
			(effects
				(font
					(size 1.27 1.27)
				)
				(justify mirror)
			)
		)
		(duplicate_pad_numbers_are_jumpers no)
		(fp_line
			(start 0.299974 -0.150114)
			(end -0.299974 -0.150114)
			(stroke
				(width 0.1)
				(type default)
			)
			(layer "B.Fab")
		)
		(fp_line
			(start -0.299974 -0.150114)
			(end -0.299974 0.150114)
			(stroke
				(width 0.1)
				(type default)
			)
			(layer "B.Fab")
		)
		(fp_line
			(start 0.299974 0.150114)
			(end 0.299974 -0.150114)
			(stroke
				(width 0.1)
				(type default)
			)
			(layer "B.Fab")
		)
		(fp_line
			(start -0.299974 0.150114)
			(end 0.299974 0.150114)
			(stroke
				(width 0.1)
				(type default)
			)
			(layer "B.Fab")
		)
		(pad "1" smd rect
			(at 0.2667 0 270)
			(size 0.3048 0.381)
			(layers "B.Cu" "B.Mask" "B.Paste")
			(net "P0V8_SERDES_VDDA_PEX3")
		)
		(pad "2" smd rect
			(at -0.2667 0 270)
			(size 0.3048 0.381)
			(layers "B.Cu" "B.Mask" "B.Paste")
			(net "GND")
		)
	)
	(footprint ""
		(layer "B.Cu")
		(at 187.854844 -98.552)
		(property "Reference" "R155"
			(at 0 0 0)
			(layer "B.SilkS")
			(hide yes)
			(effects
				(font
					(size 1.27 1.27)
				)
				(justify mirror)
			)
		)
		(property "Value" ""
			(at 0 0 0)
			(layer "B.Fab")
			(effects
				(font
					(size 1.27 1.27)
				)
				(justify mirror)
			)
		)
		(duplicate_pad_numbers_are_jumpers no)
		(fp_line
			(start -0.7874 -0.4064)
			(end -0.7874 0.4064)
			(stroke
				(width 0.1524)
				(type default)
			)
			(layer "B.SilkS")
		)
		(fp_line
			(start -0.7874 0.4064)
			(end 0.7874 0.4064)
			(stroke
				(width 0.1524)
				(type default)
			)
			(layer "B.SilkS")
		)
		(fp_line
			(start 0.7874 -0.4064)
			(end -0.7874 -0.4064)
			(stroke
				(width 0.1524)
				(type default)
			)
			(layer "B.SilkS")
		)
		(fp_line
			(start 0.7874 0.4064)
			(end 0.7874 -0.4064)
			(stroke
				(width 0.1524)
				(type default)
			)
			(layer "B.SilkS")
		)
		(fp_line
			(start -0.67945 -0.3048)
			(end -0.67945 0.3048)
			(stroke
				(width 0.1)
				(type default)
			)
			(layer "B.Fab")
		)
		(fp_line
			(start -0.67945 0.3048)
			(end -0.120396 0.3048)
			(stroke
				(width 0.1)
				(type default)
			)
			(layer "B.Fab")
		)
		(fp_line
			(start -0.12065 -0.3048)
			(end -0.67945 -0.3048)
			(stroke
				(width 0.1)
				(type default)
			)
			(layer "B.Fab")
		)
		(fp_line
			(start -0.12065 -0.2794)
			(end -0.12065 -0.3048)
			(stroke
				(width 0.1)
				(type default)
			)
			(layer "B.Fab")
		)
		(fp_line
			(start -0.120396 0.2794)
			(end 0.12065 0.2794)
			(stroke
				(width 0.1)
				(type default)
			)
			(layer "B.Fab")
		)
		(fp_line
			(start -0.120396 0.3048)
			(end -0.120396 0.2794)
			(stroke
				(width 0.1)
				(type default)
			)
			(layer "B.Fab")
		)
		(fp_line
			(start 0.12065 -0.305054)
			(end 0.12065 -0.2794)
			(stroke
				(width 0.1)
				(type default)
			)
			(layer "B.Fab")
		)
		(fp_line
			(start 0.12065 -0.2794)
			(end -0.12065 -0.2794)
			(stroke
				(width 0.1)
				(type default)
			)
			(layer "B.Fab")
		)
		(fp_line
			(start 0.12065 0.2794)
			(end 0.12065 0.3048)
			(stroke
				(width 0.1)
				(type default)
			)
			(layer "B.Fab")
		)
		(fp_line
			(start 0.12065 0.3048)
			(end 0.67945 0.3048)
			(stroke
				(width 0.1)
				(type default)
			)
			(layer "B.Fab")
		)
		(fp_line
			(start 0.67945 -0.305054)
			(end 0.12065 -0.305054)
			(stroke
				(width 0.1)
				(type default)
			)
			(layer "B.Fab")
		)
		(fp_line
			(start 0.67945 0.3048)
			(end 0.67945 -0.305054)
			(stroke
				(width 0.1)
				(type default)
			)
			(layer "B.Fab")
		)
		(pad "1" smd circle
			(at 0.40005 0 180)
			(size 0 0)
			(layers "B.Cu" "B.Mask" "B.Paste")
			(net "NIC3_MAIN_PWR_EN_R")
		)
		(pad "2" smd circle
			(at -0.40005 0 180)
			(size 0 0)
			(layers "B.Cu" "B.Mask" "B.Paste")
			(net "NIC3_MAIN_PWR_EN")
		)
	)
)
